(kicad_pcb
	(version 20260206)
	(generator "pcbnew")
	(generator_version "10.0")
	(general
		(thickness 1.6)
		(legacy_teardrops no)
	)
	(paper "A4")
	(title_block
		(title "v1-chassis-manager — T6M_CM_d_v01_1031_1645.brd")
		(comment 1 "Open CloudServer (Microsoft) / footprints 668-677 of 2512")
	)
	(layers
		(0 "F.Cu" signal "TOP")
		(4 "In1.Cu" signal "GND1")
		(6 "In2.Cu" signal "IN1")
		(8 "In3.Cu" signal "VCC1")
		(10 "In4.Cu" signal "VCC2")
		(12 "In5.Cu" signal "GND2")
		(14 "In6.Cu" signal "IN2")
		(16 "In7.Cu" signal "IN3")
		(18 "In8.Cu" signal "GND3")
		(2 "B.Cu" signal "BOTTOM")
		(9 "F.Adhes" user "F.Adhesive")
		(11 "B.Adhes" user "B.Adhesive")
		(13 "F.Paste" user "Package Geometry/Pastemask Top")
		(15 "B.Paste" user "Package Geometry/Pastemask Bottom")
		(5 "F.SilkS" user "Ref Des/Silkscreen Top")
		(7 "B.SilkS" user "Ref Des/Silkscreen Bottom")
		(1 "F.Mask" user "Board Geometry/Soldermask Top")
		(3 "B.Mask" user "Board Geometry/Soldermask Bottom")
		(17 "Dwgs.User" user "User.Drawings")
		(19 "Cmts.User" user "User.Comments")
		(21 "Eco1.User" user "User.Eco1")
		(23 "Eco2.User" user "User.Eco2")
		(25 "Edge.Cuts" user "Board Geometry/Outline")
		(27 "Margin" user)
		(31 "F.CrtYd" user "Package Geometry/Place Bound Top")
		(29 "B.CrtYd" user "Package Geometry/Place Bound Bottom")
		(35 "F.Fab" user "Ref Des/Assembly Top")
		(33 "B.Fab" user "Ref Des/Assembly Bottom")
	)
	(footprint ""
		(layer "F.Cu")
		(at 124.757434 -50.075846 90)
		(property "Reference" "R621"
			(at 17.662906 32.213804 90)
			(unlocked yes)
			(layer "F.SilkS")
			(effects
				(font
					(size 0.7874 0.5842)
					(thickness 0.1524)
				)
				(justify left)
			)
		)
		(property "Value" ""
			(at 0 0 90)
			(layer "F.Fab")
			(effects
				(font
					(size 1.27 1.27)
				)
			)
		)
		(duplicate_pad_numbers_are_jumpers no)
		(fp_line
			(start 0.7874 -0.4064)
			(end 0.7874 0.4064)
			(stroke
				(width 0.1524)
				(type default)
			)
			(layer "F.SilkS")
		)
		(fp_line
			(start -0.7874 -0.4064)
			(end 0.7874 -0.4064)
			(stroke
				(width 0.1524)
				(type default)
			)
			(layer "F.SilkS")
		)
		(fp_line
			(start 0.7874 0.4064)
			(end -0.7874 0.4064)
			(stroke
				(width 0.1524)
				(type default)
			)
			(layer "F.SilkS")
		)
		(fp_line
			(start -0.7874 0.4064)
			(end -0.7874 -0.4064)
			(stroke
				(width 0.1524)
				(type default)
			)
			(layer "F.SilkS")
		)
		(fp_poly
			(pts
				(xy -0.508 0.2794) (xy -0.508 0.2286) (xy -0.635 0.2286) (xy -0.635 -0.254) (xy -0.5334 -0.254)
				(xy -0.5334 -0.2794) (xy 0.5334 -0.2794) (xy 0.5334 -0.254) (xy 0.635 -0.254) (xy 0.635 0.254) (xy 0.5334 0.254)
				(xy 0.5334 0.2794)
			)
			(stroke
				(width 0)
				(type default)
			)
			(fill no)
			(layer "F.CrtYd")
		)
		(pad "1" smd rect
			(at 0.40005 0 90)
			(size 0.4572 0.508)
			(layers "F.Cu" "F.Mask" "F.Paste")
			(net "FM_CPLD_NODE1_CPU_RESET_L")
		)
		(pad "2" smd rect
			(at -0.40005 0 90)
			(size 0.4572 0.508)
			(layers "F.Cu" "F.Mask" "F.Paste")
			(net "SIO_LRESET_N")
		)
	)
	(footprint ""
		(layer "F.Cu")
		(at 72.132698 -17.679416 90)
		(property "Reference" "C159"
			(at -4.60629 6.316472 90)
			(unlocked yes)
			(layer "F.SilkS")
			(effects
				(font
					(size 0.7874 0.5842)
					(thickness 0.1524)
				)
				(justify left)
			)
		)
		(property "Value" ""
			(at 0 0 90)
			(layer "F.Fab")
			(effects
				(font
					(size 1.27 1.27)
				)
			)
		)
		(duplicate_pad_numbers_are_jumpers no)
		(fp_line
			(start 0.7874 -0.4064)
			(end 0.7874 0.4064)
			(stroke
				(width 0.1524)
				(type default)
			)
			(layer "F.SilkS")
		)
		(fp_line
			(start -0.7874 -0.4064)
			(end 0.7874 -0.4064)
			(stroke
				(width 0.1524)
				(type default)
			)
			(layer "F.SilkS")
		)
		(fp_line
			(start 0 0.381)
			(end 0 -0.381)
			(stroke
				(width 0.1524)
				(type default)
			)
			(layer "F.SilkS")
		)
		(fp_line
			(start 0.7874 0.4064)
			(end -0.7874 0.4064)
			(stroke
				(width 0.1524)
				(type default)
			)
			(layer "F.SilkS")
		)
		(fp_line
			(start -0.7874 0.4064)
			(end -0.7874 -0.4064)
			(stroke
				(width 0.1524)
				(type default)
			)
			(layer "F.SilkS")
		)
		(fp_poly
			(pts
				(xy -0.5334 0.254) (xy -0.635 0.254) (xy -0.635 0.2286) (xy -0.635 -0.254) (xy -0.5334 -0.254) (xy -0.5334 -0.2794)
				(xy 0.5334 -0.2794) (xy 0.5334 -0.254) (xy 0.635 -0.254) (xy 0.635 0.254) (xy 0.5334 0.254) (xy 0.5334 0.2794)
				(xy -0.508 0.2794) (xy -0.5334 0.2794)
			)
			(stroke
				(width 0)
				(type default)
			)
			(fill no)
			(layer "F.CrtYd")
		)
		(pad "1" smd rect
			(at 0.40005 0 90)
			(size 0.4572 0.508)
			(layers "F.Cu" "F.Mask" "F.Paste")
			(net "PV_VDDR_NODE1")
		)
		(pad "2" smd rect
			(at -0.40005 0 90)
			(size 0.4572 0.508)
			(layers "F.Cu" "F.Mask" "F.Paste")
			(net "GND")
		)
	)
	(footprint ""
		(layer "F.Cu")
		(at 151.494998 -142.88643 -90)
		(property "Reference" "R569"
			(at -1.458214 1.006602 90)
			(unlocked yes)
			(layer "F.SilkS")
			(effects
				(font
					(size 0.635 0.4064)
					(thickness 0.1524)
				)
				(justify left)
			)
		)
		(property "Value" ""
			(at 0 0 270)
			(layer "F.Fab")
			(effects
				(font
					(size 1.27 1.27)
				)
			)
		)
		(duplicate_pad_numbers_are_jumpers no)
		(fp_line
			(start -0.7874 0.4064)
			(end -0.7874 -0.4064)
			(stroke
				(width 0.1524)
				(type default)
			)
			(layer "F.SilkS")
		)
		(fp_line
			(start 0.7874 0.4064)
			(end -0.7874 0.4064)
			(stroke
				(width 0.1524)
				(type default)
			)
			(layer "F.SilkS")
		)
		(fp_line
			(start -0.7874 -0.4064)
			(end 0.7874 -0.4064)
			(stroke
				(width 0.1524)
				(type default)
			)
			(layer "F.SilkS")
		)
		(fp_line
			(start 0.7874 -0.4064)
			(end 0.7874 0.4064)
			(stroke
				(width 0.1524)
				(type default)
			)
			(layer "F.SilkS")
		)
		(fp_poly
			(pts
				(xy -0.508 0.2794) (xy -0.508 0.2286) (xy -0.635 0.2286) (xy -0.635 -0.254) (xy -0.5334 -0.254)
				(xy -0.5334 -0.2794) (xy 0.5334 -0.2794) (xy 0.5334 -0.254) (xy 0.635 -0.254) (xy 0.635 0.254) (xy 0.5334 0.254)
				(xy 0.5334 0.2794)
			)
			(stroke
				(width 0)
				(type default)
			)
			(fill no)
			(layer "F.CrtYd")
		)
		(pad "1" smd rect
			(at 0.40005 0 270)
			(size 0.4572 0.508)
			(layers "F.Cu" "F.Mask" "F.Paste")
			(net "P3V3_NODE1")
		)
		(pad "2" smd rect
			(at -0.40005 0 270)
			(size 0.4572 0.508)
			(layers "F.Cu" "F.Mask" "F.Paste")
			(net "SMB_LAN2_ALT_N")
		)
	)
	(footprint ""
		(layer "F.Cu")
		(at 121.65076 -188.126624 -90)
		(property "Reference" "R979"
			(at -4.967986 0.237998 90)
			(unlocked yes)
			(layer "F.SilkS")
			(effects
				(font
					(size 0.7874 0.5842)
					(thickness 0.1524)
				)
				(justify left)
			)
		)
		(property "Value" ""
			(at 0 0 270)
			(layer "F.Fab")
			(effects
				(font
					(size 1.27 1.27)
				)
			)
		)
		(duplicate_pad_numbers_are_jumpers no)
		(fp_line
			(start -0.7874 0.4064)
			(end -0.7874 -0.4064)
			(stroke
				(width 0.1524)
				(type default)
			)
			(layer "F.SilkS")
		)
		(fp_line
			(start 0.7874 0.4064)
			(end -0.7874 0.4064)
			(stroke
				(width 0.1524)
				(type default)
			)
			(layer "F.SilkS")
		)
		(fp_line
			(start -0.7874 -0.4064)
			(end 0.7874 -0.4064)
			(stroke
				(width 0.1524)
				(type default)
			)
			(layer "F.SilkS")
		)
		(fp_line
			(start 0.7874 -0.4064)
			(end 0.7874 0.4064)
			(stroke
				(width 0.1524)
				(type default)
			)
			(layer "F.SilkS")
		)
		(fp_poly
			(pts
				(xy -0.508 0.2794) (xy -0.508 0.2286) (xy -0.635 0.2286) (xy -0.635 -0.254) (xy -0.5334 -0.254)
				(xy -0.5334 -0.2794) (xy 0.5334 -0.2794) (xy 0.5334 -0.254) (xy 0.635 -0.254) (xy 0.635 0.254) (xy 0.5334 0.254)
				(xy 0.5334 0.2794)
			)
			(stroke
				(width 0)
				(type default)
			)
			(fill no)
			(layer "F.CrtYd")
		)
		(pad "1" smd rect
			(at 0.40005 0 270)
			(size 0.4572 0.508)
			(layers "F.Cu" "F.Mask" "F.Paste")
			(net "UART_T8_NODE1_RXD")
		)
		(pad "2" smd rect
			(at -0.40005 0 270)
			(size 0.4572 0.508)
			(layers "F.Cu" "F.Mask" "F.Paste")
			(net "UART_T8_NODE1_RXD_R")
		)
	)
	(footprint ""
		(layer "F.Cu")
		(at 6.73862 -151.331168 180)
		(property "Reference" "R1300"
			(at -0.99822 -0.96647 0)
			(unlocked yes)
			(layer "F.SilkS")
			(effects
				(font
					(size 0.7874 0.5842)
					(thickness 0.1524)
				)
				(justify left)
			)
		)
		(property "Value" ""
			(at 0 0 180)
			(layer "F.Fab")
			(effects
				(font
					(size 1.27 1.27)
				)
			)
		)
		(duplicate_pad_numbers_are_jumpers no)
		(fp_line
			(start 0.7874 0.4064)
			(end -0.7874 0.4064)
			(stroke
				(width 0.1524)
				(type default)
			)
			(layer "F.SilkS")
		)
		(fp_line
			(start 0.7874 -0.4064)
			(end 0.7874 0.4064)
			(stroke
				(width 0.1524)
				(type default)
			)
			(layer "F.SilkS")
		)
		(fp_line
			(start -0.7874 0.4064)
			(end -0.7874 -0.4064)
			(stroke
				(width 0.1524)
				(type default)
			)
			(layer "F.SilkS")
		)
		(fp_line
			(start -0.7874 -0.4064)
			(end 0.7874 -0.4064)
			(stroke
				(width 0.1524)
				(type default)
			)
			(layer "F.SilkS")
		)
		(fp_poly
			(pts
				(xy -0.508 0.2794) (xy -0.508 0.2286) (xy -0.635 0.2286) (xy -0.635 -0.254) (xy -0.5334 -0.254)
				(xy -0.5334 -0.2794) (xy 0.5334 -0.2794) (xy 0.5334 -0.254) (xy 0.635 -0.254) (xy 0.635 0.254) (xy 0.5334 0.254)
				(xy 0.5334 0.2794)
			)
			(stroke
				(width 0)
				(type default)
			)
			(fill no)
			(layer "F.CrtYd")
		)
		(pad "1" smd rect
			(at 0.40005 0 180)
			(size 0.4572 0.508)
			(layers "F.Cu" "F.Mask" "F.Paste")
			(net "GND")
		)
		(pad "2" smd rect
			(at -0.40005 0 180)
			(size 0.4572 0.508)
			(layers "F.Cu" "F.Mask" "F.Paste")
			(net "N54310531")
		)
	)
	(footprint ""
		(layer "F.Cu")
		(at 140.34516 -117.006624)
		(property "Reference" "R18"
			(at -0.907796 -1.867408 0)
			(unlocked yes)
			(layer "F.SilkS")
			(effects
				(font
					(size 0.7874 0.5842)
					(thickness 0.1524)
				)
				(justify left)
			)
		)
		(property "Value" ""
			(at 0 0 0)
			(layer "F.Fab")
			(effects
				(font
					(size 1.27 1.27)
				)
			)
		)
		(duplicate_pad_numbers_are_jumpers no)
		(fp_line
			(start -0.7874 -0.4064)
			(end 0.7874 -0.4064)
			(stroke
				(width 0.1524)
				(type default)
			)
			(layer "F.SilkS")
		)
		(fp_line
			(start -0.7874 0.4064)
			(end -0.7874 -0.4064)
			(stroke
				(width 0.1524)
				(type default)
			)
			(layer "F.SilkS")
		)
		(fp_line
			(start 0.7874 -0.4064)
			(end 0.7874 0.4064)
			(stroke
				(width 0.1524)
				(type default)
			)
			(layer "F.SilkS")
		)
		(fp_line
			(start 0.7874 0.4064)
			(end -0.7874 0.4064)
			(stroke
				(width 0.1524)
				(type default)
			)
			(layer "F.SilkS")
		)
		(fp_poly
			(pts
				(xy -0.508 0.2794) (xy -0.508 0.2286) (xy -0.635 0.2286) (xy -0.635 -0.254) (xy -0.5334 -0.254)
				(xy -0.5334 -0.2794) (xy 0.5334 -0.2794) (xy 0.5334 -0.254) (xy 0.635 -0.254) (xy 0.635 0.254) (xy 0.5334 0.254)
				(xy 0.5334 0.2794)
			)
			(stroke
				(width 0)
				(type default)
			)
			(fill no)
			(layer "F.CrtYd")
		)
		(pad "1" smd rect
			(at 0.40005 0)
			(size 0.4572 0.508)
			(layers "F.Cu" "F.Mask" "F.Paste")
			(net "GND")
		)
		(pad "2" smd rect
			(at -0.40005 0)
			(size 0.4572 0.508)
			(layers "F.Cu" "F.Mask" "F.Paste")
			(net "SEL_PCI_27M")
		)
	)
	(footprint ""
		(layer "F.Cu")
		(at 193.717672 -148.789898 180)
		(property "Reference" "C473"
			(at -2.357374 0.092202 0)
			(unlocked yes)
			(layer "F.SilkS")
			(effects
				(font
					(size 0.7874 0.5842)
					(thickness 0.1524)
				)
				(justify left)
			)
		)
		(property "Value" ""
			(at 0 0 180)
			(layer "F.Fab")
			(effects
				(font
					(size 1.27 1.27)
				)
			)
		)
		(duplicate_pad_numbers_are_jumpers no)
		(fp_line
			(start 1.905 0.8636)
			(end -1.905 0.8636)
			(stroke
				(width 0.1524)
				(type default)
			)
			(layer "F.SilkS")
		)
		(fp_line
			(start 1.905 -0.8636)
			(end 1.905 0.8636)
			(stroke
				(width 0.1524)
				(type default)
			)
			(layer "F.SilkS")
		)
		(fp_line
			(start 0 0.8382)
			(end 0 -0.8382)
			(stroke
				(width 0.1524)
				(type default)
			)
			(layer "F.SilkS")
		)
		(fp_line
			(start -1.905 0.8636)
			(end -1.905 -0.8636)
			(stroke
				(width 0.1524)
				(type default)
			)
			(layer "F.SilkS")
		)
		(fp_line
			(start -1.905 -0.8636)
			(end 1.905 -0.8636)
			(stroke
				(width 0.1524)
				(type default)
			)
			(layer "F.SilkS")
		)
		(fp_rect
			(start -1.524 0.7366)
			(end 1.524 -0.7366)
			(stroke
				(width 0)
				(type default)
			)
			(fill no)
			(layer "F.CrtYd")
		)
		(pad "1" smd rect
			(at 0.94996 0 180)
			(size 1.1176 1.3716)
			(layers "F.Cu" "F.Mask" "F.Paste")
			(net "P1V9_LAN2")
		)
		(pad "2" smd rect
			(at -0.94996 0 180)
			(size 1.1176 1.3716)
			(layers "F.Cu" "F.Mask" "F.Paste")
			(net "GND")
		)
	)
	(footprint ""
		(layer "F.Cu")
		(at 69.96176 -188.126624 90)
		(property "Reference" "C716"
			(at 4.548886 -0.848868 90)
			(unlocked yes)
			(layer "F.SilkS")
			(effects
				(font
					(size 0.7874 0.5842)
					(thickness 0.1524)
				)
				(justify left)
			)
		)
		(property "Value" ""
			(at 0 0 90)
			(layer "F.Fab")
			(effects
				(font
					(size 1.27 1.27)
				)
			)
		)
		(duplicate_pad_numbers_are_jumpers no)
		(fp_line
			(start 0.7874 -0.4064)
			(end 0.7874 0.4064)
			(stroke
				(width 0.1524)
				(type default)
			)
			(layer "F.SilkS")
		)
		(fp_line
			(start -0.7874 -0.4064)
			(end 0.7874 -0.4064)
			(stroke
				(width 0.1524)
				(type default)
			)
			(layer "F.SilkS")
		)
		(fp_line
			(start 0 0.381)
			(end 0 -0.381)
			(stroke
				(width 0.1524)
				(type default)
			)
			(layer "F.SilkS")
		)
		(fp_line
			(start 0.7874 0.4064)
			(end -0.7874 0.4064)
			(stroke
				(width 0.1524)
				(type default)
			)
			(layer "F.SilkS")
		)
		(fp_line
			(start -0.7874 0.4064)
			(end -0.7874 -0.4064)
			(stroke
				(width 0.1524)
				(type default)
			)
			(layer "F.SilkS")
		)
		(fp_poly
			(pts
				(xy -0.5334 0.254) (xy -0.635 0.254) (xy -0.635 0.2286) (xy -0.635 -0.254) (xy -0.5334 -0.254) (xy -0.5334 -0.2794)
				(xy 0.5334 -0.2794) (xy 0.5334 -0.254) (xy 0.635 -0.254) (xy 0.635 0.254) (xy 0.5334 0.254) (xy 0.5334 0.2794)
				(xy -0.508 0.2794) (xy -0.5334 0.2794)
			)
			(stroke
				(width 0)
				(type default)
			)
			(fill no)
			(layer "F.CrtYd")
		)
		(pad "1" smd rect
			(at 0.40005 0 90)
			(size 0.4572 0.508)
			(layers "F.Cu" "F.Mask" "F.Paste")
			(net "UART_T4_NODE4_TXD_R")
		)
		(pad "2" smd rect
			(at -0.40005 0 90)
			(size 0.4572 0.508)
			(layers "F.Cu" "F.Mask" "F.Paste")
			(net "GND")
		)
	)
	(footprint ""
		(layer "F.Cu")
		(at 52.223162 -146.530822 180)
		(property "Reference" "R549"
			(at 2.1336 -5.284978 0)
			(unlocked yes)
			(layer "F.SilkS")
			(effects
				(font
					(size 0.7874 0.5842)
					(thickness 0.1524)
				)
				(justify left)
			)
		)
		(property "Value" ""
			(at 0 0 180)
			(layer "F.Fab")
			(effects
				(font
					(size 1.27 1.27)
				)
			)
		)
		(duplicate_pad_numbers_are_jumpers no)
		(fp_line
			(start 0.7874 0.4064)
			(end -0.7874 0.4064)
			(stroke
				(width 0.1524)
				(type default)
			)
			(layer "F.SilkS")
		)
		(fp_line
			(start 0.7874 -0.4064)
			(end 0.7874 0.4064)
			(stroke
				(width 0.1524)
				(type default)
			)
			(layer "F.SilkS")
		)
		(fp_line
			(start -0.7874 0.4064)
			(end -0.7874 -0.4064)
			(stroke
				(width 0.1524)
				(type default)
			)
			(layer "F.SilkS")
		)
		(fp_line
			(start -0.7874 -0.4064)
			(end 0.7874 -0.4064)
			(stroke
				(width 0.1524)
				(type default)
			)
			(layer "F.SilkS")
		)
		(fp_poly
			(pts
				(xy -0.508 0.2794) (xy -0.508 0.2286) (xy -0.635 0.2286) (xy -0.635 -0.254) (xy -0.5334 -0.254)
				(xy -0.5334 -0.2794) (xy 0.5334 -0.2794) (xy 0.5334 -0.254) (xy 0.635 -0.254) (xy 0.635 0.254) (xy 0.5334 0.254)
				(xy 0.5334 0.2794)
			)
			(stroke
				(width 0)
				(type default)
			)
			(fill no)
			(layer "F.CrtYd")
		)
		(pad "1" smd rect
			(at 0.40005 0 180)
			(size 0.4572 0.508)
			(layers "F.Cu" "F.Mask" "F.Paste")
			(net "SPI_LAN1_NVM_SO")
		)
		(pad "2" smd rect
			(at -0.40005 0 180)
			(size 0.4572 0.508)
			(layers "F.Cu" "F.Mask" "F.Paste")
			(net "LAN1_NVM_SO_R")
		)
	)
	(footprint ""
		(layer "F.Cu")
		(at 44.207176 -179.317904 180)
		(property "Reference" "C774"
			(at 0.96012 -132.59308 0)
			(unlocked yes)
			(layer "F.SilkS")
			(effects
				(font
					(size 0.7874 0.5842)
					(thickness 0.1524)
				)
				(justify left)
			)
		)
		(property "Value" ""
			(at 0 0 180)
			(layer "F.Fab")
			(effects
				(font
					(size 1.27 1.27)
				)
			)
		)
		(duplicate_pad_numbers_are_jumpers no)
		(fp_line
			(start 0.7874 0.4064)
			(end -0.7874 0.4064)
			(stroke
				(width 0.1524)
				(type default)
			)
			(layer "F.SilkS")
		)
		(fp_line
			(start 0.7874 -0.4064)
			(end 0.7874 0.4064)
			(stroke
				(width 0.1524)
				(type default)
			)
			(layer "F.SilkS")
		)
		(fp_line
			(start 0 0.381)
			(end 0 -0.381)
			(stroke
				(width 0.1524)
				(type default)
			)
			(layer "F.SilkS")
		)
		(fp_line
			(start -0.7874 0.4064)
			(end -0.7874 -0.4064)
			(stroke
				(width 0.1524)
				(type default)
			)
			(layer "F.SilkS")
		)
		(fp_line
			(start -0.7874 -0.4064)
			(end 0.7874 -0.4064)
			(stroke
				(width 0.1524)
				(type default)
			)
			(layer "F.SilkS")
		)
		(fp_poly
			(pts
				(xy -0.5334 0.254) (xy -0.635 0.254) (xy -0.635 0.2286) (xy -0.635 -0.254) (xy -0.5334 -0.254) (xy -0.5334 -0.2794)
				(xy 0.5334 -0.2794) (xy 0.5334 -0.254) (xy 0.635 -0.254) (xy 0.635 0.254) (xy 0.5334 0.254) (xy 0.5334 0.2794)
				(xy -0.508 0.2794) (xy -0.5334 0.2794)
			)
			(stroke
				(width 0)
				(type default)
			)
			(fill no)
			(layer "F.CrtYd")
		)
		(pad "1" smd rect
			(at 0.40005 0 180)
			(size 0.4572 0.508)
			(layers "F.Cu" "F.Mask" "F.Paste")
			(net "P12V_AUX")
		)
		(pad "2" smd rect
			(at -0.40005 0 180)
			(size 0.4572 0.508)
			(layers "F.Cu" "F.Mask" "F.Paste")
			(net "GND")
		)
	)
)
